# BASEBOARD_FAB2 (Tioga Pass) — schematic netlist excerpt (pin names and nets, part order shuffled) for the footprints in the layout excerpt that follows; sources: Cadence DE-HDL packaged netlist, KiCad conversion of Wiwynn_Tioga_Pass_MB.brd

R32W11  RES  0.0 5% CHIP  pkg 0402  page 185 : A = SMB_M2_SDA ; B = SMB_M2_SDA_R
R3W3  RES  10.0K 1% EMPTY  pkg 0402  page 249 : A = P3V3_STBY ; B = FM_TPM_PRES_RST_N
C4T1  CAP_A  1.0UF 6.3V 10% X6S  pkg 0402V  page 194 : A = P1V8_MCP_CPU0 ; B = GND

(kicad_pcb
	(version 20260206)
	(generator "pcbnew")
	(generator_version "10.0")
	(general
		(thickness 1.6)
		(legacy_teardrops no)
	)
	(paper "A4")
	(title_block
		(title "Wiwynn_Tioga_Pass_MB.brd")
		(comment 1 "Tioga Pass / footprints 3573-3575 of 4770")
	)
	(layers
		(0 "F.Cu" signal "TOP")
		(4 "In1.Cu" signal "L2GND")
		(6 "In2.Cu" signal "L3")
		(8 "In3.Cu" signal "L4GND")
		(10 "In4.Cu" signal "L5")
		(12 "In5.Cu" signal "L6GND")
		(14 "In6.Cu" signal "L7VCC")
		(16 "In7.Cu" signal "L8VCC")
		(18 "In8.Cu" signal "L9GND")
		(20 "In9.Cu" signal "L10")
		(22 "In10.Cu" signal "L11GND")
		(24 "In11.Cu" signal "L12")
		(26 "In12.Cu" signal "L13GND")
		(2 "B.Cu" signal "BOTTOM")
		(9 "F.Adhes" user "F.Adhesive")
		(11 "B.Adhes" user "B.Adhesive")
		(13 "F.Paste" user "Package Geometry/Pastemask Top")
		(15 "B.Paste" user "Package Geometry/Pastemask Bottom")
		(5 "F.SilkS" user "Ref Des/Silkscreen Top")
		(7 "B.SilkS" user "Ref Des/Silkscreen Bottom")
		(1 "F.Mask" user "Board Geometry/Soldermask Top")
		(3 "B.Mask" user "Board Geometry/Soldermask Bottom")
		(17 "Dwgs.User" user "User.Drawings")
		(19 "Cmts.User" user "User.Comments")
		(21 "Eco1.User" user "User.Eco1")
		(23 "Eco2.User" user "User.Eco2")
		(25 "Edge.Cuts" user "Board Geometry/Outline")
		(27 "Margin" user)
		(31 "F.CrtYd" user "Package Geometry/Place Bound Top")
		(29 "B.CrtYd" user "Package Geometry/Place Bound Bottom")
		(35 "F.Fab" user "Ref Des/Assembly Top")
		(33 "B.Fab" user "Ref Des/Assembly Bottom")
	)
	(footprint ""
		(layer "B.Cu")
		(at 449.3895 -21.48078)
		(property "Reference" "R3W3"
			(at 0.8382 -0.67818 0)
			(unlocked yes)
			(layer "B.SilkS")
			(effects
				(font
					(size 0.4064 0.254)
					(thickness 0.1524)
				)
				(justify left mirror)
			)
		)
		(property "Value" ""
			(at 0 0 0)
			(layer "B.Fab")
			(effects
				(font
					(size 1.27 1.27)
				)
				(justify mirror)
			)
		)
		(duplicate_pad_numbers_are_jumpers no)
		(fp_poly
			(pts
				(xy 0.2794 -0.1016) (xy -0.2794 -0.1016) (xy -0.2794 0.9906) (xy 0.2794 0.9906)
			)
			(stroke
				(width 0)
				(type default)
			)
			(fill no)
			(layer "B.CrtYd")
		)
		(fp_line
			(start -0.2794 -0.1016)
			(end 0.2794 -0.1016)
			(stroke
				(width 0.1)
				(type default)
			)
			(layer "B.Fab")
		)
		(fp_line
			(start -0.2794 0.9906)
			(end -0.2794 -0.1016)
			(stroke
				(width 0.1)
				(type default)
			)
			(layer "B.Fab")
		)
		(fp_line
			(start 0.2794 -0.1016)
			(end 0.2794 0.9906)
			(stroke
				(width 0.1)
				(type default)
			)
			(layer "B.Fab")
		)
		(fp_line
			(start 0.2794 0.9906)
			(end -0.2794 0.9906)
			(stroke
				(width 0.1)
				(type default)
			)
			(layer "B.Fab")
		)
		(pad "1" smd rect
			(at 0 0 180)
			(size 0.508 0.508)
			(layers "B.Cu" "B.Mask" "B.Paste")
			(net "P3V3_STBY")
		)
		(pad "2" smd rect
			(at 0 0.889 180)
			(size 0.508 0.508)
			(layers "B.Cu" "B.Mask" "B.Paste")
			(net "FM_TPM_PRES_RST_N")
		)
		(zone
			(layer "B.Cu")
			(hatch none 0.5)
			(connect_pads
				(clearance 0)
			)
			(min_thickness 0.25)
			(keepout
				(tracks allowed)
				(vias not_allowed)
				(pads allowed)
				(copperpour not_allowed)
				(footprints allowed)
			)
			(placement
				(enabled no)
				(sheetname "")
			)
			(fill
				(thermal_gap 0.5)
				(thermal_bridge_width 0.5)
				(island_removal_mode 0)
			)
			(polygon
				(pts
					(xy 449.6435 -21.22678) (xy 449.1355 -21.22678) (xy 449.1355 -20.84578) (xy 449.6435 -20.84578)
				)
			)
		)
		(zone
			(layer "B.Cu")
			(hatch none 0.5)
			(connect_pads
				(clearance 0)
			)
			(min_thickness 0.25)
			(keepout
				(tracks not_allowed)
				(vias allowed)
				(pads allowed)
				(copperpour not_allowed)
				(footprints allowed)
			)
			(placement
				(enabled no)
				(sheetname "")
			)
			(fill
				(thermal_gap 0.5)
				(thermal_bridge_width 0.5)
				(island_removal_mode 0)
			)
			(polygon
				(pts
					(xy 449.6435 -20.84578) (xy 449.1355 -20.84578) (xy 449.1355 -21.22678) (xy 449.6435 -21.22678)
				)
			)
		)
	)
	(footprint ""
		(layer "B.Cu")
		(at 332.028038 -37.815266)
		(property "Reference" "C4T1"
			(at 0 0 0)
			(layer "B.SilkS")
			(hide yes)
			(effects
				(font
					(size 1.27 1.27)
				)
				(justify mirror)
			)
		)
		(property "Value" ""
			(at 0 0 0)
			(layer "B.Fab")
			(effects
				(font
					(size 1.27 1.27)
				)
				(justify mirror)
			)
		)
		(duplicate_pad_numbers_are_jumpers no)
		(fp_poly
			(pts
				(xy -0.3048 -0.1016) (xy -0.3048 0.9906) (xy 0.3048 0.9906) (xy 0.3048 -0.1016)
			)
			(stroke
				(width 0)
				(type default)
			)
			(fill no)
			(layer "B.CrtYd")
		)
		(fp_line
			(start -0.3048 -0.1016)
			(end 0.3048 -0.1016)
			(stroke
				(width 0.1)
				(type default)
			)
			(layer "B.Fab")
		)
		(fp_line
			(start -0.3048 0.9906)
			(end -0.3048 -0.1016)
			(stroke
				(width 0.1)
				(type default)
			)
			(layer "B.Fab")
		)
		(fp_line
			(start 0.3048 -0.1016)
			(end 0.3048 0.9906)
			(stroke
				(width 0.1)
				(type default)
			)
			(layer "B.Fab")
		)
		(fp_line
			(start 0.3048 0.9906)
			(end -0.3048 0.9906)
			(stroke
				(width 0.1)
				(type default)
			)
			(layer "B.Fab")
		)
		(pad "1" smd rect
			(at 0 0 180)
			(size 0.508 0.508)
			(layers "B.Cu" "B.Mask" "B.Paste")
			(net "P1V8_MCP_CPU0")
		)
		(pad "2" smd rect
			(at 0 0.889 180)
			(size 0.508 0.508)
			(layers "B.Cu" "B.Mask" "B.Paste")
			(net "GND")
		)
		(zone
			(layer "B.Cu")
			(hatch none 0.5)
			(connect_pads
				(clearance 0)
			)
			(min_thickness 0.25)
			(keepout
				(tracks allowed)
				(vias not_allowed)
				(pads allowed)
				(copperpour not_allowed)
				(footprints allowed)
			)
			(placement
				(enabled no)
				(sheetname "")
			)
			(fill
				(thermal_gap 0.5)
				(thermal_bridge_width 0.5)
				(island_removal_mode 0)
			)
			(polygon
				(pts
					(xy 332.282038 -37.561266) (xy 331.774038 -37.561266) (xy 331.774038 -37.180266) (xy 332.282038 -37.180266)
				)
			)
		)
		(zone
			(layer "B.Cu")
			(hatch none 0.5)
			(connect_pads
				(clearance 0)
			)
			(min_thickness 0.25)
			(keepout
				(tracks not_allowed)
				(vias allowed)
				(pads allowed)
				(copperpour not_allowed)
				(footprints allowed)
			)
			(placement
				(enabled no)
				(sheetname "")
			)
			(fill
				(thermal_gap 0.5)
				(thermal_bridge_width 0.5)
				(island_removal_mode 0)
			)
			(polygon
				(pts
					(xy 332.282038 -37.180266) (xy 331.774038 -37.180266) (xy 331.774038 -37.561266) (xy 332.282038 -37.561266)
				)
			)
		)
	)
	(footprint ""
		(layer "B.Cu")
		(at 393.2047 -10.01903 180)
		(property "Reference" "R32W11"
			(at 0.8382 -0.67818 180)
			(unlocked yes)
			(layer "B.SilkS")
			(effects
				(font
					(size 0.4064 0.254)
					(thickness 0.1524)
				)
				(justify left mirror)
			)
		)
		(property "Value" ""
			(at 0 0 0)
			(layer "B.Fab")
			(effects
				(font
					(size 1.27 1.27)
				)
				(justify mirror)
			)
		)
		(duplicate_pad_numbers_are_jumpers no)
		(fp_poly
			(pts
				(xy 0.2794 -0.1016) (xy -0.2794 -0.1016) (xy -0.2794 0.9906) (xy 0.2794 0.9906)
			)
			(stroke
				(width 0)
				(type default)
			)
			(fill no)
			(layer "B.CrtYd")
		)
		(fp_line
			(start 0.2794 0.9906)
			(end -0.2794 0.9906)
			(stroke
				(width 0.1)
				(type default)
			)
			(layer "B.Fab")
		)
		(fp_line
			(start 0.2794 -0.1016)
			(end 0.2794 0.9906)
			(stroke
				(width 0.1)
				(type default)
			)
			(layer "B.Fab")
		)
		(fp_line
			(start -0.2794 0.9906)
			(end -0.2794 -0.1016)
			(stroke
				(width 0.1)
				(type default)
			)
			(layer "B.Fab")
		)
		(fp_line
			(start -0.2794 -0.1016)
			(end 0.2794 -0.1016)
			(stroke
				(width 0.1)
				(type default)
			)
			(layer "B.Fab")
		)
		(pad "1" smd rect
			(at 0 0)
			(size 0.508 0.508)
			(layers "B.Cu" "B.Mask" "B.Paste")
			(net "SMB_M2_SDA")
		)
		(pad "2" smd rect
			(at 0 0.889)
			(size 0.508 0.508)
			(layers "B.Cu" "B.Mask" "B.Paste")
			(net "SMB_M2_SDA_R")
		)
		(zone
			(layer "B.Cu")
			(hatch none 0.5)
			(connect_pads
				(clearance 0)
			)
			(min_thickness 0.25)
			(keepout
				(tracks not_allowed)
				(vias allowed)
				(pads allowed)
				(copperpour not_allowed)
				(footprints allowed)
			)
			(placement
				(enabled no)
				(sheetname "")
			)
			(fill
				(thermal_gap 0.5)
				(thermal_bridge_width 0.5)
				(island_removal_mode 0)
			)
			(polygon
				(pts
					(xy 392.9507 -10.65403) (xy 393.4587 -10.65403) (xy 393.4587 -10.27303) (xy 392.9507 -10.27303)
				)
			)
		)
		(zone
			(layer "B.Cu")
			(hatch none 0.5)
			(connect_pads
				(clearance 0)
			)
			(min_thickness 0.25)
			(keepout
				(tracks allowed)
				(vias not_allowed)
				(pads allowed)
				(copperpour not_allowed)
				(footprints allowed)
			)
			(placement
				(enabled no)
				(sheetname "")
			)
			(fill
				(thermal_gap 0.5)
				(thermal_bridge_width 0.5)
				(island_removal_mode 0)
			)
			(polygon
				(pts
					(xy 392.9507 -10.27303) (xy 393.4587 -10.27303) (xy 393.4587 -10.65403) (xy 392.9507 -10.65403)
				)
			)
		)
	)
)
